(kicad_pcb
	(version 20260206)
	(generator "pcbnew")
	(generator_version "10.0")
	(general
		(thickness 1.6)
		(legacy_teardrops no)
	)
	(paper "A4")
	(title_block
		(title "fcb — Lightning_FCB_BRD.brd")
		(comment 1 "Lightning (Wiwynn / Facebook NVMe JBOF) / footprints 245-250 of 495")
	)
	(layers
		(0 "F.Cu" signal "TOP")
		(4 "In1.Cu" signal "L2GND")
		(6 "In2.Cu" signal "L3VCC")
		(2 "B.Cu" signal "BOTTOM")
		(9 "F.Adhes" user "F.Adhesive")
		(11 "B.Adhes" user "B.Adhesive")
		(13 "F.Paste" user "Package Geometry/Pastemask Top")
		(15 "B.Paste" user "Package Geometry/Pastemask Bottom")
		(5 "F.SilkS" user "Ref Des/Silkscreen Top")
		(7 "B.SilkS" user "Ref Des/Silkscreen Bottom")
		(1 "F.Mask" user "Board Geometry/Soldermask Top")
		(3 "B.Mask" user "Board Geometry/Soldermask Bottom")
		(17 "Dwgs.User" user "User.Drawings")
		(19 "Cmts.User" user "User.Comments")
		(21 "Eco1.User" user "User.Eco1")
		(23 "Eco2.User" user "User.Eco2")
		(25 "Edge.Cuts" user "Board Geometry/Outline")
		(27 "Margin" user)
		(31 "F.CrtYd" user "Package Geometry/Place Bound Top")
		(29 "B.CrtYd" user "Package Geometry/Place Bound Bottom")
		(35 "F.Fab" user "Ref Des/Assembly Top")
		(33 "B.Fab" user "Ref Des/Assembly Bottom")
	)
	(footprint ""
		(layer "F.Cu")
		(at 19.558508 -288.594038)
		(property "Reference" "R103"
			(at 0 0 0)
			(layer "F.SilkS")
			(hide yes)
			(effects
				(font
					(size 1.27 1.27)
				)
			)
		)
		(property "Value" "10KR2F-2-GP"
			(at 0.064008 -3.993896 0)
			(unlocked yes)
			(layer "F.Fab")
			(hide yes)
			(effects
				(font
					(size 1.016 1.016)
					(thickness 0.1524)
				)
			)
		)
		(property "Device Type" "R402H16"
			(at 0.064008 -5.517896 0)
			(unlocked yes)
			(layer "F.Fab")
			(hide yes)
			(effects
				(font
					(size 1.016 1.016)
					(thickness 0.1524)
				)
			)
		)
		(duplicate_pad_numbers_are_jumpers no)
		(fp_line
			(start -0.508 -0.9398)
			(end -0.508 0.9398)
			(stroke
				(width 0.1524)
				(type default)
			)
			(layer "F.SilkS")
		)
		(fp_line
			(start 0.508 -0.9398)
			(end -0.508 -0.9398)
			(stroke
				(width 0.1524)
				(type default)
			)
			(layer "F.SilkS")
		)
		(fp_rect
			(start -0.508 0.9398)
			(end 0.508 -0.9398)
			(stroke
				(width 0)
				(type default)
			)
			(fill no)
			(layer "F.CrtYd")
		)
		(fp_rect
			(start -0.508 0.9398)
			(end 0.508 -0.9398)
			(stroke
				(width 0)
				(type default)
			)
			(fill no)
			(layer "F.Fab")
		)
		(pad "1" smd custom
			(at 0 -0.4445)
			(size 0.1397 0.1397)
			(layers "F.Cu" "F.Mask" "F.Paste")
			(net "FANIN_4")
			(options
				(clearance outline)
				(anchor circle)
			)
			(primitives
				(gr_poly
					(pts
						(arc
							(start -0.1778 -0.2794)
							(mid -0.249642 -0.249642)
							(end -0.2794 -0.1778)
						)
						(arc
							(start -0.2794 0.1778)
							(mid -0.249642 0.249642)
							(end -0.1778 0.2794)
						)
						(arc
							(start 0.1778 0.2794)
							(mid 0.249642 0.249642)
							(end 0.2794 0.1778)
						)
						(arc
							(start 0.2794 -0.1778)
							(mid 0.249642 -0.249642)
							(end 0.1778 -0.2794)
						)
					)
					(width 0)
					(fill yes)
				)
			)
		)
		(pad "2" smd custom
			(at 0 0.4445)
			(size 0.1397 0.1397)
			(layers "F.Cu" "F.Mask" "F.Paste")
			(net "GND")
			(options
				(clearance outline)
				(anchor circle)
			)
			(primitives
				(gr_poly
					(pts
						(arc
							(start -0.1778 -0.2794)
							(mid -0.249642 -0.249642)
							(end -0.2794 -0.1778)
						)
						(arc
							(start -0.2794 0.1778)
							(mid -0.249642 0.249642)
							(end -0.1778 0.2794)
						)
						(arc
							(start 0.1778 0.2794)
							(mid 0.249642 0.249642)
							(end 0.2794 0.1778)
						)
						(arc
							(start 0.2794 -0.1778)
							(mid 0.249642 -0.249642)
							(end 0.1778 -0.2794)
						)
					)
					(width 0)
					(fill yes)
				)
			)
		)
	)
	(footprint ""
		(layer "F.Cu")
		(at 14.8082 -66.4464 180)
		(property "Reference" "R150"
			(at 0 0 180)
			(layer "F.SilkS")
			(hide yes)
			(effects
				(font
					(size 1.27 1.27)
				)
			)
		)
		(property "Value" "10R2F-L-GP"
			(at 0.064008 -3.993896 180)
			(unlocked yes)
			(layer "F.Fab")
			(hide yes)
			(effects
				(font
					(size 1.016 1.016)
					(thickness 0.1524)
				)
			)
		)
		(property "Device Type" "R402H14"
			(at 0.064008 -5.517896 180)
			(unlocked yes)
			(layer "F.Fab")
			(hide yes)
			(effects
				(font
					(size 1.016 1.016)
					(thickness 0.1524)
				)
			)
		)
		(duplicate_pad_numbers_are_jumpers no)
		(fp_line
			(start 0.508 -0.9398)
			(end -0.508 -0.9398)
			(stroke
				(width 0.1524)
				(type default)
			)
			(layer "F.SilkS")
		)
		(fp_line
			(start -0.508 -0.9398)
			(end -0.508 0.9398)
			(stroke
				(width 0.1524)
				(type default)
			)
			(layer "F.SilkS")
		)
		(fp_rect
			(start -0.508 0.9398)
			(end 0.508 -0.9398)
			(stroke
				(width 0)
				(type default)
			)
			(fill no)
			(layer "F.CrtYd")
		)
		(fp_rect
			(start -0.508 0.9398)
			(end 0.508 -0.9398)
			(stroke
				(width 0)
				(type default)
			)
			(fill no)
			(layer "F.Fab")
		)
		(pad "1" smd custom
			(at 0 -0.4445 180)
			(size 0.1397 0.1397)
			(layers "F.Cu" "F.Mask" "F.Paste")
			(net "I2C_C_SDA_CONN_R")
			(options
				(clearance outline)
				(anchor circle)
			)
			(primitives
				(gr_poly
					(pts
						(arc
							(start -0.1778 -0.2794)
							(mid -0.249642 -0.249642)
							(end -0.2794 -0.1778)
						)
						(arc
							(start -0.2794 0.1778)
							(mid -0.249642 0.249642)
							(end -0.1778 0.2794)
						)
						(arc
							(start 0.1778 0.2794)
							(mid 0.249642 0.249642)
							(end 0.2794 0.1778)
						)
						(arc
							(start 0.2794 -0.1778)
							(mid 0.249642 -0.249642)
							(end 0.1778 -0.2794)
						)
					)
					(width 0)
					(fill yes)
				)
			)
		)
		(pad "2" smd custom
			(at 0 0.4445 180)
			(size 0.1397 0.1397)
			(layers "F.Cu" "F.Mask" "F.Paste")
			(net "I2C_C_SDA")
			(options
				(clearance outline)
				(anchor circle)
			)
			(primitives
				(gr_poly
					(pts
						(arc
							(start -0.1778 -0.2794)
							(mid -0.249642 -0.249642)
							(end -0.2794 -0.1778)
						)
						(arc
							(start -0.2794 0.1778)
							(mid -0.249642 0.249642)
							(end -0.1778 0.2794)
						)
						(arc
							(start 0.1778 0.2794)
							(mid 0.249642 0.249642)
							(end 0.2794 0.1778)
						)
						(arc
							(start 0.2794 -0.1778)
							(mid 0.249642 -0.249642)
							(end 0.1778 -0.2794)
						)
					)
					(width 0)
					(fill yes)
				)
			)
		)
	)
	(footprint ""
		(layer "F.Cu")
		(at 43.815 -389.001 90)
		(property "Reference" "TC9"
			(at 0 0 90)
			(layer "F.SilkS")
			(hide yes)
			(effects
				(font
					(size 1.27 1.27)
				)
			)
		)
		(property "Value" "ST68U16VDM-1-GP"
			(at 0 -9.6012 90)
			(unlocked yes)
			(layer "F.Fab")
			(hide yes)
			(effects
				(font
					(size 1.016 1.016)
					(thickness 0.1524)
				)
			)
		)
		(property "Device Type" "CT7343H79"
			(at 0 -11.1252 90)
			(unlocked yes)
			(layer "F.Fab")
			(hide yes)
			(effects
				(font
					(size 1.016 1.016)
					(thickness 0.1524)
				)
			)
		)
		(duplicate_pad_numbers_are_jumpers no)
		(fp_line
			(start 2.286 -4.8768)
			(end -2.286 -4.8768)
			(stroke
				(width 0.1524)
				(type default)
			)
			(layer "F.SilkS")
		)
		(fp_line
			(start -2.286 -4.8768)
			(end -2.286 -2.032)
			(stroke
				(width 0.1524)
				(type default)
			)
			(layer "F.SilkS")
		)
		(fp_line
			(start 2.1082 -4.699)
			(end -2.1082 -4.699)
			(stroke
				(width 0.508)
				(type default)
			)
			(layer "F.SilkS")
		)
		(fp_line
			(start 2.286 -2.032)
			(end 2.286 -4.8768)
			(stroke
				(width 0.1524)
				(type default)
			)
			(layer "F.SilkS")
		)
		(fp_line
			(start 2.286 2.032)
			(end 2.286 4.8768)
			(stroke
				(width 0.1524)
				(type default)
			)
			(layer "F.SilkS")
		)
		(fp_line
			(start 2.286 4.8768)
			(end -2.286 4.8768)
			(stroke
				(width 0.1524)
				(type default)
			)
			(layer "F.SilkS")
		)
		(fp_line
			(start -2.286 4.8768)
			(end -2.286 2.032)
			(stroke
				(width 0.1524)
				(type default)
			)
			(layer "F.SilkS")
		)
		(fp_rect
			(start -2.1463 3.6449)
			(end 2.1463 -3.6449)
			(stroke
				(width 0)
				(type default)
			)
			(fill no)
			(layer "F.CrtYd")
		)
		(fp_poly
			(pts
				(xy -2.54 4.953) (xy -2.54 4.2926) (xy -3.81 4.2926) (xy -3.81 -4.2926) (xy -2.54 -4.2926) (xy -2.54 -4.953)
				(xy 2.54 -4.953) (xy 2.54 -4.2926) (xy 3.81 -4.2926) (xy 3.81 -1.6256) (xy 2.1463 -1.6256) (xy 2.1463 -3.6449)
				(xy -2.1463 -3.6449) (xy -2.1463 3.6449) (xy 2.1463 3.6449) (xy 2.1463 -1.6129) (xy 3.81 -1.6129)
				(xy 3.81 4.2926) (xy 2.54 4.2926) (xy 2.54 4.953)
			)
			(stroke
				(width 0)
				(type default)
			)
			(fill no)
			(layer "F.CrtYd")
		)
		(fp_rect
			(start 2.54 4.2926)
			(end 3.81 -4.2926)
			(stroke
				(width 0)
				(type default)
			)
			(fill no)
			(layer "F.Fab")
		)
		(fp_rect
			(start -3.81 4.2926)
			(end -2.54 -4.2926)
			(stroke
				(width 0)
				(type default)
			)
			(fill no)
			(layer "F.Fab")
		)
		(fp_rect
			(start -2.54 4.953)
			(end 2.54 -4.953)
			(stroke
				(width 0)
				(type default)
			)
			(fill no)
			(layer "F.Fab")
		)
		(pad "1" smd rect
			(at 0 -3.1496 90)
			(size 2.413 2.286)
			(layers "F.Cu" "F.Mask" "F.Paste")
			(net "P12V")
		)
		(pad "2" smd rect
			(at 0 3.1496 90)
			(size 2.413 2.286)
			(layers "F.Cu" "F.Mask" "F.Paste")
			(net "GND")
		)
		(zone
			(layer "F.Cu")
			(hatch none 0.5)
			(connect_pads
				(clearance 0)
			)
			(min_thickness 0.25)
			(keepout
				(tracks allowed)
				(vias not_allowed)
				(pads allowed)
				(copperpour not_allowed)
				(footprints allowed)
			)
			(placement
				(enabled no)
				(sheetname "")
			)
			(fill
				(thermal_gap 0.5)
				(thermal_bridge_width 0.5)
				(island_removal_mode 0)
			)
			(polygon
				(pts
					(xy 42.1259 -390.5123) (xy 39.2176 -390.5123) (xy 39.2176 -387.4897) (xy 42.1132 -387.4897) (xy 42.4434 -387.4897)
					(xy 42.4434 -390.5123)
				)
			)
		)
		(zone
			(layer "F.Cu")
			(hatch none 0.5)
			(connect_pads
				(clearance 0)
			)
			(min_thickness 0.25)
			(keepout
				(tracks allowed)
				(vias not_allowed)
				(pads allowed)
				(copperpour not_allowed)
				(footprints allowed)
			)
			(placement
				(enabled no)
				(sheetname "")
			)
			(fill
				(thermal_gap 0.5)
				(thermal_bridge_width 0.5)
				(island_removal_mode 0)
			)
			(polygon
				(pts
					(xy 48.4124 -387.4897) (xy 48.4124 -390.5123) (xy 45.5168 -390.5123) (xy 45.1866 -390.5123) (xy 45.1866 -387.4897)
					(xy 45.5168 -387.4897)
				)
			)
		)
	)
	(footprint ""
		(layer "F.Cu")
		(at 5.1054 -437.0578 90)
		(property "Reference" "R121"
			(at 0 0 90)
			(layer "F.SilkS")
			(hide yes)
			(effects
				(font
					(size 1.27 1.27)
				)
			)
		)
		(property "Value" "2KR2F-3-GP"
			(at 0.064008 -3.993896 90)
			(unlocked yes)
			(layer "F.Fab")
			(hide yes)
			(effects
				(font
					(size 1.016 1.016)
					(thickness 0.1524)
				)
			)
		)
		(property "Device Type" "R402H16"
			(at 0.064008 -5.517896 90)
			(unlocked yes)
			(layer "F.Fab")
			(hide yes)
			(effects
				(font
					(size 1.016 1.016)
					(thickness 0.1524)
				)
			)
		)
		(duplicate_pad_numbers_are_jumpers no)
		(fp_line
			(start 0.508 -0.9398)
			(end -0.508 -0.9398)
			(stroke
				(width 0.1524)
				(type default)
			)
			(layer "F.SilkS")
		)
		(fp_line
			(start -0.508 -0.9398)
			(end -0.508 0.9398)
			(stroke
				(width 0.1524)
				(type default)
			)
			(layer "F.SilkS")
		)
		(fp_rect
			(start -0.508 0.9398)
			(end 0.508 -0.9398)
			(stroke
				(width 0)
				(type default)
			)
			(fill no)
			(layer "F.CrtYd")
		)
		(fp_rect
			(start -0.508 0.9398)
			(end 0.508 -0.9398)
			(stroke
				(width 0)
				(type default)
			)
			(fill no)
			(layer "F.Fab")
		)
		(pad "1" smd custom
			(at 0 -0.4445 90)
			(size 0.1397 0.1397)
			(layers "F.Cu" "F.Mask" "F.Paste")
			(net "LED_DR_LED0")
			(options
				(clearance outline)
				(anchor circle)
			)
			(primitives
				(gr_poly
					(pts
						(arc
							(start -0.1778 -0.2794)
							(mid -0.249642 -0.249642)
							(end -0.2794 -0.1778)
						)
						(arc
							(start -0.2794 0.1778)
							(mid -0.249642 0.249642)
							(end -0.1778 0.2794)
						)
						(arc
							(start 0.1778 0.2794)
							(mid 0.249642 0.249642)
							(end 0.2794 0.1778)
						)
						(arc
							(start 0.2794 -0.1778)
							(mid 0.249642 -0.249642)
							(end 0.1778 -0.2794)
						)
					)
					(width 0)
					(fill yes)
				)
			)
		)
		(pad "2" smd custom
			(at 0 0.4445 90)
			(size 0.1397 0.1397)
			(layers "F.Cu" "F.Mask" "F.Paste")
			(net "LED_DR_LED0_B")
			(options
				(clearance outline)
				(anchor circle)
			)
			(primitives
				(gr_poly
					(pts
						(arc
							(start -0.1778 -0.2794)
							(mid -0.249642 -0.249642)
							(end -0.2794 -0.1778)
						)
						(arc
							(start -0.2794 0.1778)
							(mid -0.249642 0.249642)
							(end -0.1778 0.2794)
						)
						(arc
							(start 0.1778 0.2794)
							(mid 0.249642 0.249642)
							(end 0.2794 0.1778)
						)
						(arc
							(start 0.2794 -0.1778)
							(mid 0.249642 -0.249642)
							(end 0.1778 -0.2794)
						)
					)
					(width 0)
					(fill yes)
				)
			)
		)
	)
	(footprint ""
		(layer "F.Cu")
		(at 44.069 -178.0794 90)
		(property "Reference" "R270"
			(at 0 0 90)
			(layer "F.SilkS")
			(hide yes)
			(effects
				(font
					(size 1.27 1.27)
				)
			)
		)
		(property "Value" "0R2J-2-GP"
			(at 0.064008 -3.993896 90)
			(unlocked yes)
			(layer "F.Fab")
			(hide yes)
			(effects
				(font
					(size 1.016 1.016)
					(thickness 0.1524)
				)
			)
		)
		(property "Device Type" "R402H16"
			(at 0.064008 -5.517896 90)
			(unlocked yes)
			(layer "F.Fab")
			(hide yes)
			(effects
				(font
					(size 1.016 1.016)
					(thickness 0.1524)
				)
			)
		)
		(duplicate_pad_numbers_are_jumpers no)
		(fp_line
			(start 0.508 -0.9398)
			(end -0.508 -0.9398)
			(stroke
				(width 0.1524)
				(type default)
			)
			(layer "F.SilkS")
		)
		(fp_line
			(start -0.508 -0.9398)
			(end -0.508 0.9398)
			(stroke
				(width 0.1524)
				(type default)
			)
			(layer "F.SilkS")
		)
		(fp_rect
			(start -0.508 0.9398)
			(end 0.508 -0.9398)
			(stroke
				(width 0)
				(type default)
			)
			(fill no)
			(layer "F.CrtYd")
		)
		(fp_rect
			(start -0.508 0.9398)
			(end 0.508 -0.9398)
			(stroke
				(width 0)
				(type default)
			)
			(fill no)
			(layer "F.Fab")
		)
		(pad "1" smd custom
			(at 0 -0.4445 90)
			(size 0.1397 0.1397)
			(layers "F.Cu" "F.Mask" "F.Paste")
			(net "D_LATCH_Q")
			(options
				(clearance outline)
				(anchor circle)
			)
			(primitives
				(gr_poly
					(pts
						(arc
							(start -0.1778 -0.2794)
							(mid -0.249642 -0.249642)
							(end -0.2794 -0.1778)
						)
						(arc
							(start -0.2794 0.1778)
							(mid -0.249642 0.249642)
							(end -0.1778 0.2794)
						)
						(arc
							(start 0.1778 0.2794)
							(mid 0.249642 0.249642)
							(end 0.2794 0.1778)
						)
						(arc
							(start 0.2794 -0.1778)
							(mid 0.249642 -0.249642)
							(end 0.1778 -0.2794)
						)
					)
					(width 0)
					(fill yes)
				)
			)
		)
		(pad "2" smd custom
			(at 0 0.4445 90)
			(size 0.1397 0.1397)
			(layers "F.Cu" "F.Mask" "F.Paste")
			(net "ADM1276_EN")
			(options
				(clearance outline)
				(anchor circle)
			)
			(primitives
				(gr_poly
					(pts
						(arc
							(start -0.1778 -0.2794)
							(mid -0.249642 -0.249642)
							(end -0.2794 -0.1778)
						)
						(arc
							(start -0.2794 0.1778)
							(mid -0.249642 0.249642)
							(end -0.1778 0.2794)
						)
						(arc
							(start 0.1778 0.2794)
							(mid 0.249642 0.249642)
							(end 0.2794 0.1778)
						)
						(arc
							(start 0.2794 -0.1778)
							(mid 0.249642 -0.249642)
							(end 0.1778 -0.2794)
						)
					)
					(width 0)
					(fill yes)
				)
			)
		)
	)
	(footprint ""
		(layer "F.Cu")
		(at 5.1562 -417.6522 90)
		(property "Reference" "R27"
			(at 0 0 90)
			(layer "F.SilkS")
			(hide yes)
			(effects
				(font
					(size 1.27 1.27)
				)
			)
		)
		(property "Value" "33R2F-3-GP"
			(at 0.064008 -3.993896 90)
			(unlocked yes)
			(layer "F.Fab")
			(hide yes)
			(effects
				(font
					(size 1.016 1.016)
					(thickness 0.1524)
				)
			)
		)
		(property "Device Type" "R402H16"
			(at 0.064008 -5.517896 90)
			(unlocked yes)
			(layer "F.Fab")
			(hide yes)
			(effects
				(font
					(size 1.016 1.016)
					(thickness 0.1524)
				)
			)
		)
		(duplicate_pad_numbers_are_jumpers no)
		(fp_line
			(start 0.508 -0.9398)
			(end -0.508 -0.9398)
			(stroke
				(width 0.1524)
				(type default)
			)
			(layer "F.SilkS")
		)
		(fp_line
			(start -0.508 -0.9398)
			(end -0.508 0.9398)
			(stroke
				(width 0.1524)
				(type default)
			)
			(layer "F.SilkS")
		)
		(fp_rect
			(start -0.508 0.9398)
			(end 0.508 -0.9398)
			(stroke
				(width 0)
				(type default)
			)
			(fill no)
			(layer "F.CrtYd")
		)
		(fp_rect
			(start -0.508 0.9398)
			(end 0.508 -0.9398)
			(stroke
				(width 0)
				(type default)
			)
			(fill no)
			(layer "F.Fab")
		)
		(pad "1" smd custom
			(at 0 -0.4445 90)
			(size 0.1397 0.1397)
			(layers "F.Cu" "F.Mask" "F.Paste")
			(net "P3V3")
			(options
				(clearance outline)
				(anchor circle)
			)
			(primitives
				(gr_poly
					(pts
						(arc
							(start -0.1778 -0.2794)
							(mid -0.249642 -0.249642)
							(end -0.2794 -0.1778)
						)
						(arc
							(start -0.2794 0.1778)
							(mid -0.249642 0.249642)
							(end -0.1778 0.2794)
						)
						(arc
							(start 0.1778 0.2794)
							(mid 0.249642 0.249642)
							(end 0.2794 0.1778)
						)
						(arc
							(start 0.2794 -0.1778)
							(mid 0.249642 -0.249642)
							(end 0.1778 -0.2794)
						)
					)
					(width 0)
					(fill yes)
				)
			)
		)
		(pad "2" smd custom
			(at 0 0.4445 90)
			(size 0.1397 0.1397)
			(layers "F.Cu" "F.Mask" "F.Paste")
			(net "LED_DR_LED1_BLUE")
			(options
				(clearance outline)
				(anchor circle)
			)
			(primitives
				(gr_poly
					(pts
						(arc
							(start -0.1778 -0.2794)
							(mid -0.249642 -0.249642)
							(end -0.2794 -0.1778)
						)
						(arc
							(start -0.2794 0.1778)
							(mid -0.249642 0.249642)
							(end -0.1778 0.2794)
						)
						(arc
							(start 0.1778 0.2794)
							(mid 0.249642 0.249642)
							(end 0.2794 0.1778)
						)
						(arc
							(start 0.2794 -0.1778)
							(mid 0.249642 -0.249642)
							(end 0.1778 -0.2794)
						)
					)
					(width 0)
					(fill yes)
				)
			)
		)
	)
)
